(kicad_pcb
	(version 20260206)
	(generator "pcbnew")
	(generator_version "10.0")
	(general
		(thickness 1.6)
		(legacy_teardrops no)
	)
	(paper "A4")
	(title_block
		(title "03242023_DA0F0TMBIJ0_F0T_Motherboard_J_brd_V01_OCP.brd")
		(comment 1 "Grand Teton / footprint 1682 of 6105 (U1), pads 1708-1819 of 4677")
	)
	(layers
		(0 "F.Cu" signal "TOP")
		(4 "In1.Cu" signal "GND")
		(6 "In2.Cu" signal "IN1")
		(8 "In3.Cu" signal "GND1")
		(10 "In4.Cu" signal "IN2")
		(12 "In5.Cu" signal "GND2")
		(14 "In6.Cu" signal "IN3")
		(16 "In7.Cu" signal "GND3")
		(18 "In8.Cu" signal "VCC")
		(20 "In9.Cu" signal "VCC1")
		(22 "In10.Cu" signal "GND4")
		(24 "In11.Cu" signal "IN4")
		(26 "In12.Cu" signal "GND5")
		(28 "In13.Cu" signal "IN5")
		(30 "In14.Cu" signal "GND6")
		(32 "In15.Cu" signal "IN6")
		(34 "In16.Cu" signal "GND7")
		(2 "B.Cu" signal "BOTTOM")
		(9 "F.Adhes" user "F.Adhesive")
		(11 "B.Adhes" user "B.Adhesive")
		(13 "F.Paste" user "Package Geometry/Pastemask Top")
		(15 "B.Paste" user "Package Geometry/Pastemask Bottom")
		(5 "F.SilkS" user "Ref Des/Silkscreen Top")
		(7 "B.SilkS" user "Ref Des/Silkscreen Bottom")
		(1 "F.Mask" user "Board Geometry/Soldermask Top")
		(3 "B.Mask" user "Board Geometry/Soldermask Bottom")
		(17 "Dwgs.User" user "User.Drawings")
		(19 "Cmts.User" user "User.Comments")
		(21 "Eco1.User" user "User.Eco1")
		(23 "Eco2.User" user "User.Eco2")
		(25 "Edge.Cuts" user "Board Geometry/Outline")
		(27 "Margin" user)
		(31 "F.CrtYd" user "Package Geometry/Place Bound Top")
		(29 "B.CrtYd" user "Package Geometry/Place Bound Bottom")
		(35 "F.Fab" user "Ref Des/Assembly Top")
		(33 "B.Fab" user "Ref Des/Assembly Bottom")
	)
	(footprint ""
		(layer "F.Cu")
		(at 111.93018 -251.76988 90)
		(property "Reference" "U1"
			(at -74.913236 41.548812 0)
			(unlocked yes)
			(layer "F.SilkS")
			(effects
				(font
					(size 1.6002 1.1938)
					(thickness 0.1524)
				)
				(justify left)
			)
		)
		(property "Value" ""
			(at 0 0 90)
			(layer "F.Fab")
			(effects
				(font
					(size 1.27 1.27)
				)
			)
		)
		(duplicate_pad_numbers_are_jumpers no)
		(pad "CA66" smd circle
			(at 17.07769 1.229614 270)
			(size 0.4318 0.4318)
			(layers "F.Cu" "F.Mask" "F.Paste")
			(net "PVCCIN_CPU1")
		)
		(pad "CA68" smd circle
			(at 18.705576 1.229614 270)
			(size 0.4318 0.4318)
			(layers "F.Cu" "F.Mask" "F.Paste")
			(net "PVCCIN_CPU1")
		)
		(pad "CA70" smd circle
			(at 20.333462 1.229614 270)
			(size 0.4318 0.4318)
			(layers "F.Cu" "F.Mask" "F.Paste")
			(net "PVCCIN_CPU1")
		)
		(pad "CA72" smd circle
			(at 21.961094 1.229614 270)
			(size 0.4318 0.4318)
			(layers "F.Cu" "F.Mask" "F.Paste")
			(net "PVCCIN_CPU1")
		)
		(pad "CA74" smd circle
			(at 23.58898 1.229614 270)
			(size 0.4318 0.4318)
			(layers "F.Cu" "F.Mask" "F.Paste")
			(net "PVCCIN_CPU1")
		)
		(pad "CA76" smd circle
			(at 25.216612 1.229614 270)
			(size 0.4318 0.4318)
			(layers "F.Cu" "F.Mask" "F.Paste")
			(net "PVCCIN_CPU1")
		)
		(pad "CA78" smd circle
			(at 26.844498 1.229614 270)
			(size 0.4318 0.4318)
			(layers "F.Cu" "F.Mask" "F.Paste")
			(net "PVCCIN_CPU1")
		)
		(pad "CA80" smd circle
			(at 28.472384 1.229614 270)
			(size 0.4318 0.4318)
			(layers "F.Cu" "F.Mask" "F.Paste")
			(net "PVCCIN_CPU1")
		)
		(pad "CA82" smd circle
			(at 30.100016 1.229614 270)
			(size 0.4318 0.4318)
			(layers "F.Cu" "F.Mask" "F.Paste")
			(net "PVCCIN_CPU1")
		)
		(pad "CA84" smd circle
			(at 31.727902 1.229614 270)
			(size 0.4318 0.4318)
			(layers "F.Cu" "F.Mask" "F.Paste")
			(net "PVCCIN_CPU1")
		)
		(pad "CA86" smd circle
			(at 33.355534 1.229614 270)
			(size 0.4318 0.4318)
			(layers "F.Cu" "F.Mask" "F.Paste")
			(net "PVCCIN_CPU1")
		)
		(pad "CA88" smd circle
			(at 34.98342 1.229614 270)
			(size 0.4318 0.4318)
			(layers "F.Cu" "F.Mask" "F.Paste")
			(net "PVCCIN_CPU1")
		)
		(pad "CA90" smd oval
			(at 36.611306 1.229614)
			(size 0.381 0.4826)
			(drill
				(offset 0 -0.0508)
			)
			(layers "F.Cu" "F.Mask" "F.Paste")
			(net "PVCCIN_CPU1")
		)
		(pad "CB2" smd oval
			(at -36.611306 1.589532 180)
			(size 0.381 0.4826)
			(drill
				(offset 0 -0.0508)
			)
			(layers "F.Cu" "F.Mask" "F.Paste")
			(net "UPI_CPU0_CPU1_P0P1_DN<23>")
		)
		(pad "CB4" smd circle
			(at -34.98342 1.589532 270)
			(size 0.4318 0.4318)
			(layers "F.Cu" "F.Mask" "F.Paste")
			(net "GND")
		)
		(pad "CB6" smd circle
			(at -33.355534 1.589532 270)
			(size 0.4318 0.4318)
			(layers "F.Cu" "F.Mask" "F.Paste")
			(net "UPI_CPU1_CPU0_P1P0_DP<22>")
		)
		(pad "CB8" smd circle
			(at -31.727902 1.589532 270)
			(size 0.4318 0.4318)
			(layers "F.Cu" "F.Mask" "F.Paste")
			(net "GND")
		)
		(pad "CB10" smd circle
			(at -30.100016 1.589532 270)
			(size 0.4318 0.4318)
			(layers "F.Cu" "F.Mask" "F.Paste")
			(net "P5E_CPU1_PE1_RX_DN<6>")
		)
		(pad "CB12" smd circle
			(at -28.472384 1.589532 270)
			(size 0.4318 0.4318)
			(layers "F.Cu" "F.Mask" "F.Paste")
			(net "GND")
		)
		(pad "CB14" smd circle
			(at -26.844498 1.589532 270)
			(size 0.4318 0.4318)
			(layers "F.Cu" "F.Mask" "F.Paste")
			(net "P5E_CPU1_PE1_TX_DN<6>")
		)
		(pad "CB16" smd circle
			(at -25.216612 1.589532 270)
			(size 0.4318 0.4318)
			(layers "F.Cu" "F.Mask" "F.Paste")
			(net "GND")
		)
		(pad "CB18" smd circle
			(at -23.58898 1.589532 270)
			(size 0.4318 0.4318)
			(layers "F.Cu" "F.Mask" "F.Paste")
			(net "TP_DMI_CPU1_PCH_TX_DN<2>")
		)
		(pad "CB20" smd circle
			(at -21.961094 1.589532 270)
			(size 0.4318 0.4318)
			(layers "F.Cu" "F.Mask" "F.Paste")
			(net "GND")
		)
		(pad "CB22" smd circle
			(at -20.333462 1.589532 270)
			(size 0.4318 0.4318)
			(layers "F.Cu" "F.Mask" "F.Paste")
			(net "GND")
		)
		(pad "CB24" smd circle
			(at -18.705576 1.589532 270)
			(size 0.4318 0.4318)
			(layers "F.Cu" "F.Mask" "F.Paste")
			(net "GND")
		)
		(pad "CB26" smd circle
			(at -17.07769 1.589532 270)
			(size 0.4318 0.4318)
			(layers "F.Cu" "F.Mask" "F.Paste")
			(net "GND")
		)
		(pad "CB28" smd circle
			(at -15.450058 1.589532 270)
			(size 0.4318 0.4318)
			(layers "F.Cu" "F.Mask" "F.Paste")
			(net "GND")
		)
		(pad "CB30" smd circle
			(at -13.822426 1.589532 270)
			(size 0.4318 0.4318)
			(layers "F.Cu" "F.Mask" "F.Paste")
			(net "TP_TRC_CPU1_PTI0_CLK")
		)
		(pad "CB32" smd circle
			(at -12.19454 1.589532 270)
			(size 0.4318 0.4318)
			(layers "F.Cu" "F.Mask" "F.Paste")
			(net "GND")
		)
		(pad "CB34" smd circle
			(at -10.566654 1.589532 270)
			(size 0.4318 0.4318)
			(layers "F.Cu" "F.Mask" "F.Paste")
			(net "GND")
		)
		(pad "CB36" smd circle
			(at -8.939022 1.589532 270)
			(size 0.4318 0.4318)
			(layers "F.Cu" "F.Mask" "F.Paste")
			(net "GND")
		)
		(pad "CB38" smd circle
			(at -7.311136 1.589532 270)
			(size 0.4318 0.4318)
			(layers "F.Cu" "F.Mask" "F.Paste")
			(net "GND")
		)
		(pad "CB40" smd circle
			(at -5.68325 1.589532 270)
			(size 0.4318 0.4318)
			(layers "F.Cu" "F.Mask" "F.Paste")
			(net "GND")
		)
		(pad "CB42" smd circle
			(at -4.055618 1.589532 270)
			(size 0.4318 0.4318)
			(layers "F.Cu" "F.Mask" "F.Paste")
			(net "GND")
		)
		(pad "CB44" smd circle
			(at -2.427732 1.589532 270)
			(size 0.4318 0.4318)
			(layers "F.Cu" "F.Mask" "F.Paste")
			(net "GND")
		)
		(pad "CB47" smd circle
			(at 1.613916 1.699514 270)
			(size 0.4318 0.4318)
			(layers "F.Cu" "F.Mask" "F.Paste")
			(net "GND")
		)
		(pad "CB49" smd circle
			(at 3.241802 1.699514 270)
			(size 0.4318 0.4318)
			(layers "F.Cu" "F.Mask" "F.Paste")
			(net "GND")
		)
		(pad "CB51" smd circle
			(at 4.869434 1.699514 270)
			(size 0.4318 0.4318)
			(layers "F.Cu" "F.Mask" "F.Paste")
			(net "GND")
		)
		(pad "CB53" smd circle
			(at 6.49732 1.699514 270)
			(size 0.4318 0.4318)
			(layers "F.Cu" "F.Mask" "F.Paste")
			(net "GND")
		)
		(pad "CB55" smd circle
			(at 8.124952 1.699514 270)
			(size 0.4318 0.4318)
			(layers "F.Cu" "F.Mask" "F.Paste")
			(net "GND")
		)
		(pad "CB57" smd circle
			(at 9.752838 1.699514 270)
			(size 0.4318 0.4318)
			(layers "F.Cu" "F.Mask" "F.Paste")
			(net "GND")
		)
		(pad "CB59" smd circle
			(at 11.380724 1.699514 270)
			(size 0.4318 0.4318)
			(layers "F.Cu" "F.Mask" "F.Paste")
			(net "GND")
		)
		(pad "CB61" smd circle
			(at 13.008356 1.699514 270)
			(size 0.4318 0.4318)
			(layers "F.Cu" "F.Mask" "F.Paste")
			(net "PVCCIN_CPU1")
		)
		(pad "CB63" smd circle
			(at 14.635988 1.699514 270)
			(size 0.4318 0.4318)
			(layers "F.Cu" "F.Mask" "F.Paste")
			(net "GND")
		)
		(pad "CB65" smd circle
			(at 16.263874 1.699514 270)
			(size 0.4318 0.4318)
			(layers "F.Cu" "F.Mask" "F.Paste")
			(net "GND")
		)
		(pad "CB67" smd circle
			(at 17.89176 1.699514 270)
			(size 0.4318 0.4318)
			(layers "F.Cu" "F.Mask" "F.Paste")
			(net "GND")
		)
		(pad "CB69" smd circle
			(at 19.519392 1.699514 270)
			(size 0.4318 0.4318)
			(layers "F.Cu" "F.Mask" "F.Paste")
			(net "GND")
		)
		(pad "CB71" smd circle
			(at 21.147278 1.699514 270)
			(size 0.4318 0.4318)
			(layers "F.Cu" "F.Mask" "F.Paste")
			(net "GND")
		)
		(pad "CB73" smd circle
			(at 22.77491 1.699514 270)
			(size 0.4318 0.4318)
			(layers "F.Cu" "F.Mask" "F.Paste")
			(net "GND")
		)
		(pad "CB75" smd circle
			(at 24.402796 1.699514 270)
			(size 0.4318 0.4318)
			(layers "F.Cu" "F.Mask" "F.Paste")
			(net "PVCCIN_CPU1")
		)
		(pad "CB77" smd circle
			(at 26.030682 1.699514 270)
			(size 0.4318 0.4318)
			(layers "F.Cu" "F.Mask" "F.Paste")
			(net "PVCCIN_CPU1")
		)
		(pad "CB79" smd circle
			(at 27.658314 1.699514 270)
			(size 0.4318 0.4318)
			(layers "F.Cu" "F.Mask" "F.Paste")
			(net "GND")
		)
		(pad "CB81" smd circle
			(at 29.2862 1.699514 270)
			(size 0.4318 0.4318)
			(layers "F.Cu" "F.Mask" "F.Paste")
			(net "GND")
		)
		(pad "CB83" smd circle
			(at 30.914086 1.699514 270)
			(size 0.4318 0.4318)
			(layers "F.Cu" "F.Mask" "F.Paste")
			(net "GND")
		)
		(pad "CB85" smd circle
			(at 32.541718 1.699514 270)
			(size 0.4318 0.4318)
			(layers "F.Cu" "F.Mask" "F.Paste")
			(net "GND")
		)
		(pad "CB87" smd circle
			(at 34.169604 1.699514 270)
			(size 0.4318 0.4318)
			(layers "F.Cu" "F.Mask" "F.Paste")
			(net "GND")
		)
		(pad "CB89" smd circle
			(at 35.797236 1.699514 270)
			(size 0.4318 0.4318)
			(layers "F.Cu" "F.Mask" "F.Paste")
			(net "GND")
		)
		(pad "CC3" smd circle
			(at -35.797236 2.059686 270)
			(size 0.4318 0.4318)
			(layers "F.Cu" "F.Mask" "F.Paste")
			(net "UPI_CPU0_CPU1_P0P1_DP<22>")
		)
		(pad "CC5" smd circle
			(at -34.169604 2.059686 270)
			(size 0.4318 0.4318)
			(layers "F.Cu" "F.Mask" "F.Paste")
			(net "GND")
		)
		(pad "CC7" smd circle
			(at -32.541718 2.059686 270)
			(size 0.4318 0.4318)
			(layers "F.Cu" "F.Mask" "F.Paste")
			(net "UPI_CPU1_CPU0_P1P0_DP<21>")
		)
		(pad "CC9" smd circle
			(at -30.914086 2.059686 270)
			(size 0.4318 0.4318)
			(layers "F.Cu" "F.Mask" "F.Paste")
			(net "GND")
		)
		(pad "CC11" smd circle
			(at -29.2862 2.059686 270)
			(size 0.4318 0.4318)
			(layers "F.Cu" "F.Mask" "F.Paste")
			(net "P5E_CPU1_PE1_RX_DN<5>")
		)
		(pad "CC13" smd circle
			(at -27.658314 2.059686 270)
			(size 0.4318 0.4318)
			(layers "F.Cu" "F.Mask" "F.Paste")
			(net "GND")
		)
		(pad "CC15" smd circle
			(at -26.030682 2.059686 270)
			(size 0.4318 0.4318)
			(layers "F.Cu" "F.Mask" "F.Paste")
			(net "P5E_CPU1_PE1_TX_DP<6>")
		)
		(pad "CC17" smd circle
			(at -24.402796 2.059686 270)
			(size 0.4318 0.4318)
			(layers "F.Cu" "F.Mask" "F.Paste")
			(net "GND")
		)
		(pad "CC19" smd circle
			(at -22.77491 2.059686 270)
			(size 0.4318 0.4318)
			(layers "F.Cu" "F.Mask" "F.Paste")
			(net "TP_DMI_CPU1_PCH_TX_DP<2>")
		)
		(pad "CC21" smd circle
			(at -21.147278 2.059686 270)
			(size 0.4318 0.4318)
			(layers "F.Cu" "F.Mask" "F.Paste")
			(net "NC_CPU1_PE1_APROBE<1>")
		)
		(pad "CC23" smd circle
			(at -19.519392 2.059686 270)
			(size 0.4318 0.4318)
			(layers "F.Cu" "F.Mask" "F.Paste")
			(net "NC_CPU1_PE2_APROBE<0>")
		)
		(pad "CC25" smd circle
			(at -17.89176 2.059686 270)
			(size 0.4318 0.4318)
			(layers "F.Cu" "F.Mask" "F.Paste")
			(net "TP_H_SBLINK7_CPU1_PMDOWN")
		)
		(pad "CC27" smd circle
			(at -16.263874 2.059686 270)
			(size 0.4318 0.4318)
			(layers "F.Cu" "F.Mask" "F.Paste")
			(net "TP_TRC_CPU1_PTI<2>")
		)
		(pad "CC29" smd circle
			(at -14.635988 2.059686 270)
			(size 0.4318 0.4318)
			(layers "F.Cu" "F.Mask" "F.Paste")
			(net "TP_TRC_CPU1_PTI<0>")
		)
		(pad "CC31" smd circle
			(at -13.008356 2.059686 270)
			(size 0.4318 0.4318)
			(layers "F.Cu" "F.Mask" "F.Paste")
			(net "GND")
		)
		(pad "CC33" smd circle
			(at -11.380724 2.059686 270)
			(size 0.4318 0.4318)
			(layers "F.Cu" "F.Mask" "F.Paste")
			(net "PVCCIN_CPU1")
		)
		(pad "CC35" smd circle
			(at -9.752838 2.059686 270)
			(size 0.4318 0.4318)
			(layers "F.Cu" "F.Mask" "F.Paste")
			(net "PVCCIN_CPU1")
		)
		(pad "CC37" smd circle
			(at -8.124952 2.059686 270)
			(size 0.4318 0.4318)
			(layers "F.Cu" "F.Mask" "F.Paste")
			(net "PVCCIN_CPU1")
		)
		(pad "CC39" smd circle
			(at -6.49732 2.059686 270)
			(size 0.4318 0.4318)
			(layers "F.Cu" "F.Mask" "F.Paste")
			(net "PVCCIN_CPU1")
		)
		(pad "CC41" smd circle
			(at -4.869434 2.059686 270)
			(size 0.4318 0.4318)
			(layers "F.Cu" "F.Mask" "F.Paste")
			(net "PVCCIN_CPU1")
		)
		(pad "CC43" smd circle
			(at -3.241802 2.059686 270)
			(size 0.4318 0.4318)
			(layers "F.Cu" "F.Mask" "F.Paste")
			(net "PVCCIN_CPU1")
		)
		(pad "CC45" smd circle
			(at -1.613916 2.059686 270)
			(size 0.4318 0.4318)
			(layers "F.Cu" "F.Mask" "F.Paste")
			(net "PVCCIN_CPU1")
		)
		(pad "CC48" smd circle
			(at 2.427732 2.169668 270)
			(size 0.4318 0.4318)
			(layers "F.Cu" "F.Mask" "F.Paste")
			(net "PVCCIN_CPU1")
		)
		(pad "CC50" smd circle
			(at 4.055618 2.169668 270)
			(size 0.4318 0.4318)
			(layers "F.Cu" "F.Mask" "F.Paste")
			(net "PVCCIN_CPU1")
		)
		(pad "CC52" smd circle
			(at 5.68325 2.169668 270)
			(size 0.4318 0.4318)
			(layers "F.Cu" "F.Mask" "F.Paste")
			(net "PVCCIN_CPU1")
		)
		(pad "CC54" smd circle
			(at 7.311136 2.169668 270)
			(size 0.4318 0.4318)
			(layers "F.Cu" "F.Mask" "F.Paste")
			(net "PVCCIN_CPU1")
		)
		(pad "CC56" smd circle
			(at 8.939022 2.169668 270)
			(size 0.4318 0.4318)
			(layers "F.Cu" "F.Mask" "F.Paste")
			(net "PVCCIN_CPU1")
		)
		(pad "CC58" smd circle
			(at 10.566654 2.169668 270)
			(size 0.4318 0.4318)
			(layers "F.Cu" "F.Mask" "F.Paste")
			(net "PVCCIN_CPU1")
		)
		(pad "CC60" smd circle
			(at 12.19454 2.169668 270)
			(size 0.4318 0.4318)
			(layers "F.Cu" "F.Mask" "F.Paste")
			(net "PVCCIN_CPU1")
		)
		(pad "CC62" smd circle
			(at 13.822426 2.169668 270)
			(size 0.4318 0.4318)
			(layers "F.Cu" "F.Mask" "F.Paste")
			(net "GND")
		)
		(pad "CC64" smd circle
			(at 15.450058 2.169668 270)
			(size 0.4318 0.4318)
			(layers "F.Cu" "F.Mask" "F.Paste")
			(net "NC_CPU1_LGSSPARE4")
		)
		(pad "CC66" smd circle
			(at 17.07769 2.169668 270)
			(size 0.4318 0.4318)
			(layers "F.Cu" "F.Mask" "F.Paste")
			(net "NC_CPU1_MDFI_DIE01_EW1")
		)
		(pad "CC68" smd circle
			(at 18.705576 2.169668 270)
			(size 0.4318 0.4318)
			(layers "F.Cu" "F.Mask" "F.Paste")
			(net "PVPP_HBM_CPU1")
		)
		(pad "CC70" smd circle
			(at 20.333462 2.169668 270)
			(size 0.4318 0.4318)
			(layers "F.Cu" "F.Mask" "F.Paste")
			(net "GND")
		)
		(pad "CC72" smd circle
			(at 21.961094 2.169668 270)
			(size 0.4318 0.4318)
			(layers "F.Cu" "F.Mask" "F.Paste")
			(net "GND")
		)
		(pad "CC74" smd circle
			(at 23.58898 2.169668 270)
			(size 0.4318 0.4318)
			(layers "F.Cu" "F.Mask" "F.Paste")
			(net "GND")
		)
		(pad "CC76" smd circle
			(at 25.216612 2.169668 270)
			(size 0.4318 0.4318)
			(layers "F.Cu" "F.Mask" "F.Paste")
			(net "PVCCIN_CPU1")
		)
		(pad "CC78" smd circle
			(at 26.844498 2.169668 270)
			(size 0.4318 0.4318)
			(layers "F.Cu" "F.Mask" "F.Paste")
			(net "PVCCIN_CPU1")
		)
		(pad "CC80" smd circle
			(at 28.472384 2.169668 270)
			(size 0.4318 0.4318)
			(layers "F.Cu" "F.Mask" "F.Paste")
			(net "PVCCIN_CPU1")
		)
		(pad "CC82" smd circle
			(at 30.100016 2.169668 270)
			(size 0.4318 0.4318)
			(layers "F.Cu" "F.Mask" "F.Paste")
			(net "PVCCIN_CPU1")
		)
		(pad "CC84" smd circle
			(at 31.727902 2.169668 270)
			(size 0.4318 0.4318)
			(layers "F.Cu" "F.Mask" "F.Paste")
			(net "PVCCIN_CPU1")
		)
		(pad "CC86" smd circle
			(at 33.355534 2.169668 270)
			(size 0.4318 0.4318)
			(layers "F.Cu" "F.Mask" "F.Paste")
			(net "PVCCIN_CPU1")
		)
		(pad "CC88" smd circle
			(at 34.98342 2.169668 270)
			(size 0.4318 0.4318)
			(layers "F.Cu" "F.Mask" "F.Paste")
			(net "PVCCIN_CPU1")
		)
		(pad "CC90" smd oval
			(at 36.611306 2.169668)
			(size 0.381 0.4826)
			(drill
				(offset 0 -0.0508)
			)
			(layers "F.Cu" "F.Mask" "F.Paste")
			(net "PVCCIN_CPU1")
		)
		(pad "CD2" smd oval
			(at -36.611306 2.529586 180)
			(size 0.381 0.4826)
			(drill
				(offset 0 -0.0508)
			)
			(layers "F.Cu" "F.Mask" "F.Paste")
			(net "UPI_CPU0_CPU1_P0P1_DN<22>")
		)
		(pad "CD4" smd circle
			(at -34.98342 2.529586 270)
			(size 0.4318 0.4318)
			(layers "F.Cu" "F.Mask" "F.Paste")
			(net "GND")
		)
		(pad "CD6" smd circle
			(at -33.355534 2.529586 270)
			(size 0.4318 0.4318)
			(layers "F.Cu" "F.Mask" "F.Paste")
			(net "UPI_CPU1_CPU0_P1P0_DN<21>")
		)
		(pad "CD8" smd circle
			(at -31.727902 2.529586 270)
			(size 0.4318 0.4318)
			(layers "F.Cu" "F.Mask" "F.Paste")
			(net "GND")
		)
		(pad "CD10" smd circle
			(at -30.100016 2.529586 270)
			(size 0.4318 0.4318)
			(layers "F.Cu" "F.Mask" "F.Paste")
			(net "P5E_CPU1_PE1_RX_DP<5>")
		)
		(pad "CD12" smd circle
			(at -28.472384 2.529586 270)
			(size 0.4318 0.4318)
			(layers "F.Cu" "F.Mask" "F.Paste")
			(net "GND")
		)
		(pad "CD14" smd circle
			(at -26.844498 2.529586 270)
			(size 0.4318 0.4318)
			(layers "F.Cu" "F.Mask" "F.Paste")
			(net "P5E_CPU1_PE1_TX_DP<5>")
		)
		(pad "CD16" smd circle
			(at -25.216612 2.529586 270)
			(size 0.4318 0.4318)
			(layers "F.Cu" "F.Mask" "F.Paste")
			(net "GND")
		)
		(pad "CD18" smd circle
			(at -23.58898 2.529586 270)
			(size 0.4318 0.4318)
			(layers "F.Cu" "F.Mask" "F.Paste")
			(net "TP_DMI_CPU1_PCH_TX_DP<3>")
		)
		(pad "CD20" smd circle
			(at -21.961094 2.529586 270)
			(size 0.4318 0.4318)
			(layers "F.Cu" "F.Mask" "F.Paste")
			(net "GND")
		)
		(pad "CD22" smd circle
			(at -20.333462 2.529586 270)
			(size 0.4318 0.4318)
			(layers "F.Cu" "F.Mask" "F.Paste")
			(net "NC_CPU1_MDFI_DIE10_NS1")
		)
	)
)
